;LEADER: 12 
;HEADER: 
;CODE  : ASCII 
;FILE  : t6m_pdb_d_0928_1400_274-1-8.drl for board t6m_pdb_d_0928_1400_274.brd ... layers TOP and BOTTOM
;   Holesize 1. = 10.000000 Tolerance = +3.000000/-3.000000 PLATED MILS Quantity = 539
;   Holesize 2. = 20.000000 Tolerance = +3.000000/-3.000000 PLATED MILS Quantity = 673
;   Holesize 3. = 22.000000 Tolerance = +3.000000/-3.000000 PLATED MILS Quantity = 96
;   Holesize 4. = 28.000000 Tolerance = +2.000000/-2.000000 PLATED MILS Quantity = 328
;   Holesize 5. = 30.000000 Tolerance = +2.000000/-2.000000 PLATED MILS Quantity = 528
;   Holesize 6. = 36.000000 Tolerance = +3.000000/-3.000000 PLATED MILS Quantity = 72
;   Holesize 7. = 39.000000 Tolerance = +3.000000/-3.000000 PLATED MILS Quantity = 48
;   Holesize 8. = 40.000000 Tolerance = +3.000000/-3.000000 PLATED MILS Quantity = 8
;   Holesize 9. = 44.000000 Tolerance = +3.000000/-3.000000 PLATED MILS Quantity = 384
;   Holesize 10. = 57.000000 Tolerance = +3.000000/-3.000000 PLATED MILS Quantity = 20
;   Holesize 11. = 63.000000 Tolerance = +3.000000/-3.000000 PLATED MILS Quantity = 4
;   Holesize 12. = 95.000000 Tolerance = +2.000000/-2.000000 NON_PLATED MILS Quantity = 4
;   Holesize 13. = 99.000000 Tolerance = +2.000000/-2.000000 NON_PLATED MILS Quantity = 24
;   Holesize 14. = 126.000000 Tolerance = +2.000000/-2.000000 NON_PLATED MILS Quantity = 4
;   Holesize 15. = 132.000000 Tolerance = +2.000000/-2.000000 NON_PLATED MILS Quantity = 12
;   Holesize 16. = 158.000000 Tolerance = +2.000000/-2.000000 NON_PLATED MILS Quantity = 12
;   Holesize 17. = 205.000000 Tolerance = +2.000000/-2.000000 NON_PLATED MILS Quantity = 1
;   Holesize 18. = 315.000000 Tolerance = +4.000000/-4.000000 NON_PLATED MILS Quantity = 12
%
G90
X0025219Y0018752
X0003001Y0052034
X0003001Y0100034
X0003001Y0150034
X0003001Y0200034
X0003001Y0250034
X0003001Y0300034
X0003001Y0350034
X0003001Y0400034
X0003001Y0450034
X0003001Y0500034
X0003001Y0550034
X0058750Y0579653
X0011677Y0578766
X0003001Y0600034
X0003001Y0650034
X0059236Y0670758
X0054483Y0679810
X0057124Y0675327
X0003001Y0700034
X0003001Y0750034
X0003001Y0800034
X0003001Y0850034
X0003001Y0900034
X0003001Y0950034
X0048467Y0869278
X0048433Y0866179
X0003001Y1000034
X0003001Y1050034
X0003001Y1100034
X0003001Y1150034
X0003001Y1200034
X0003001Y1250034
X0049441Y1238962
X0054543Y1308995
X0046980Y1330843
X0046980Y1320843
X0046980Y1315843
X0046980Y1325843
X0046980Y1335843
X0046980Y1340843
X0046980Y1345843
X0054543Y1296513
X0057458Y1253378
X0003001Y1300034
X0003001Y1350034
X0058416Y1272383
X0058356Y1279812
X0059127Y1257647
X0003001Y1400034
X0003001Y1450034
X0003001Y1500034
X0003001Y1550034
X0054108Y1559138
X0011085Y1552589
X0016484Y1552159
X0003006Y1594602
X0003001Y1650034
X0003012Y1610165
X0003001Y1700034
X0003001Y1750034
X0003001Y1800034
X0003001Y1850034
X0003001Y1900034
X0003001Y1950034
X0003001Y2000034
X0003001Y2050034
X0026833Y2067866
X0076833Y2067866
X0109991Y2083607
X0106819Y1802230
X0159075Y1825087
X0108819Y1812118
X0108819Y1824470
X0159822Y1831380
X0107373Y1780544
X0107355Y1770437
X0107220Y1791589
X0107391Y1794460
X0156452Y1800821
X0105669Y1815227
X0099294Y1789947
X0099068Y1760827
X0099103Y1765722
X0098873Y1780542
X0099047Y1785571
X0156183Y1735240
X0144878Y1738861
X0150309Y1737009
X0107006Y1452651
X0108574Y1463389
X0159216Y1477124
X0113518Y1489571
X0159526Y1483434
X0095236Y1453321
X0105455Y1472894
X0106921Y1419492
X0106962Y1434041
X0106763Y1444599
X0097465Y1447919
X0097825Y1419492
X0097403Y1424340
X0096996Y1438980
X0096993Y1443743
X0159192Y1451105
X0096510Y1395382
X0158618Y1399448
X0101626Y1397635
X0067568Y1307829
X0061866Y1342104
X0061866Y1309190
X0100719Y1306810
X0100719Y1318810
X0100719Y1324810
X0100719Y1346065
X0100719Y1312810
X0100719Y1336810
X0075475Y1315303
X0067568Y1296654
X0063061Y1296312
X0100719Y1330810
X0096684Y1081791
X0158456Y1129045
X0112503Y1115860
X0108468Y1129286
X0159382Y1136151
X0107215Y1072208
X0107235Y1081791
X0105152Y1118381
X0082763Y1060051
X0107351Y1093484
X0108779Y1105760
X0156854Y1101031
X0098652Y1096403
X0096904Y1067515
X0096774Y1072226
X0096949Y1087095
X0096948Y1092036
X0105684Y1125919
X0063577Y1019115
X0060815Y1019026
X0102611Y0972220
X0105395Y0972040
X0079499Y1014871
X0076446Y1014871
X0100687Y0999391
X0098139Y0990959
X0070865Y0854278
X0070865Y0860278
X0070865Y0866278
X0090708Y0878615
X0070865Y0890116
X0070865Y0872278
X0092989Y0927334
X0070865Y0897750
X0092633Y0907404
X0092216Y0899865
X0112836Y0769122
X0158956Y0780982
X0113697Y0794293
X0159053Y0787280
X0105087Y0754126
X0101244Y0774100
X0107173Y0735219
X0107025Y0725368
X0095775Y0751469
X0106935Y0745139
X0061888Y0666012
X0098124Y0745139
X0098564Y0715937
X0098591Y0720745
X0097534Y0735248
X0097443Y0739962
X0156610Y0751063
X0063820Y0579654
X0158807Y0432969
X0111017Y0419566
X0159019Y0439268
X0109475Y0434743
X0106709Y0391219
X0106836Y0376461
X0094347Y0421562
X0093223Y0417736
X0114498Y0396207
X0105451Y0406795
X0156865Y0401207
X0101990Y0426104
X0097643Y0396024
X0097985Y0391220
X0097457Y0371909
X0097536Y0376580
X0109054Y0058250
X0107263Y0072244
X0158901Y0085017
X0159417Y0091281
X0107213Y0085169
X0104350Y0062293
X0225219Y0003002
X0175219Y0003002
X0104116Y0082557
X0257125Y0115559
X0256947Y0128276
X0106958Y0026285
X0107037Y0034687
X0157558Y0051426
X0107405Y0049898
X0101430Y0041803
X0102646Y0049461
X0108082Y0038899
X0097417Y0037438
X0097417Y0032853
X0106335Y0022580
X0125219Y0003002
X0162384Y0056744
X0162586Y0068130
X0161742Y0072497
X0075219Y0018752
X0161339Y0088108
X0161377Y0407575
X0161257Y0420869
X0161517Y0436119
X0255687Y0812192
X0255837Y0823626
X0161826Y0756757
X0161644Y0764231
X0161131Y0774878
X0161479Y0784141
X0176011Y0936829
X0175989Y0944537
X0184284Y0948331
X0175449Y0997660
X0175742Y0989958
X0175022Y0980281
X0175135Y0972490
X0175561Y0955964
X0175359Y0963486
X0175473Y1016296
X0175698Y1008730
X0175897Y1023997
X0175448Y1031766
X0188385Y1020810
X0184118Y1019280
X0184353Y1001556
X0184632Y0983423
X0184196Y0967371
X0162140Y1106853
X0164539Y1116135
X0170351Y1401324
X0164037Y1400226
X0176083Y1402321
X0162242Y1471380
X0163099Y1457084
X0162524Y1462651
X0163257Y1737619
X0165782Y1732903
X0168151Y1739208
X0173394Y1736051
X0162140Y1807740
X0163250Y1815631
X0161844Y1828225
X0159991Y2083607
X0209991Y2083607
X0259991Y2083607
X0309991Y2083607
X0320045Y1990215
X0314562Y1994087
X0324803Y1990272
X0279976Y1864565
X0280240Y1858668
X0293606Y1858668
X0273817Y1913327
X0278262Y1913327
X0282717Y1913327
X0287121Y1913327
X0292614Y1864565
X0332399Y1926787
X0347676Y1922165
X0340336Y1922409
X0344402Y1911123
X0338309Y1927623
X0345537Y1916558
X0358318Y1920680
X0286623Y1814400
X0291550Y1814846
X0281066Y1819569
X0335730Y1753270
X0321283Y1753466
X0329887Y1752081
X0311539Y1753499
X0289499Y1738735
X0284583Y1738465
X0279703Y1738398
X0274704Y1738196
X0289421Y1641558
X0284086Y1644883
X0285054Y1558211
X0289675Y1558211
X0294392Y1558211
X0298870Y1558211
X0294090Y1641558
X0335963Y1573797
X0333474Y1566686
X0355364Y1570990
X0317243Y1574832
X0329399Y1571939
X0312077Y1575871
X0348245Y1575241
X0343402Y1572080
X0323720Y1570924
X0348710Y1570187
X0301734Y1513883
X0302267Y1524401
X0313894Y1513883
X0279990Y1464435
X0275521Y1464435
X0270234Y1467760
X0270579Y1389626
X0275052Y1389715
X0279518Y1389543
X0284240Y1389544
X0350690Y1403243
X0344130Y1401670
X0334646Y1400804
X0325636Y1399114
X0319404Y1401346
X0314183Y1403423
X0329619Y1284016
X0327932Y1289221
X0333242Y1276809
X0338047Y1282599
X0321978Y1282086
X0327452Y1279447
X0289210Y1290634
X0283808Y1293959
X0294133Y1290634
X0312698Y1172804
X0312527Y1162266
X0325796Y1162266
X0279559Y1206777
X0284194Y1206777
X0289082Y1206777
X0293807Y1206777
X0323403Y1172804
X0317592Y1053050
X0349855Y1104302
X0344099Y1106798
X0337509Y1109598
X0326558Y1126368
X0331920Y1116088
X0328989Y1121090
X0309678Y1053262
X0292698Y1116146
X0288188Y1116146
X0282958Y1119471
X0335677Y1048904
X0345578Y1047844
X0324246Y1051786
X0290107Y1031162
X0294617Y1031162
X0281124Y1031162
X0285666Y1031162
X0328583Y0933262
X0343656Y0933725
X0336160Y0937262
X0333300Y0928464
X0326646Y0939788
X0323868Y0929978
X0318557Y0941178
X0324098Y0946104
X0321425Y0951577
X0339615Y0926357
X0332527Y0943746
X0329938Y0948756
X0281305Y0862237
X0285788Y0862237
X0285874Y0941442
X0281194Y0941442
X0275966Y0944767
X0272181Y0862354
X0276686Y0862488
X0327524Y0758020
X0334010Y0758588
X0339012Y0752859
X0329336Y0762693
X0331568Y0752967
X0270070Y0812192
X0282737Y0767643
X0278184Y0767643
X0273114Y0770968
X0344109Y0751809
X0278955Y0687192
X0283340Y0687192
X0270109Y0687192
X0274514Y0687192
X0320380Y0576491
X0342900Y0580126
X0321742Y0599041
X0319852Y0593330
X0323751Y0589155
X0333750Y0595326
X0337387Y0586230
X0331867Y0589810
X0317724Y0588250
X0329636Y0584715
X0319305Y0582111
X0336617Y0577978
X0290984Y0592215
X0285348Y0595540
X0295509Y0592215
X0265737Y0473680
X0265722Y0463102
X0274991Y0463099
X0269516Y0512341
X0273938Y0512341
X0278405Y0512341
X0282776Y0512341
X0328950Y0409216
X0326196Y0413982
X0342097Y0401684
X0320980Y0423225
X0323313Y0418313
X0335522Y0404033
X0291002Y0417844
X0286665Y0417844
X0281569Y0421169
X0289895Y0337688
X0294506Y0337688
X0281074Y0337688
X0285513Y0337688
X0305867Y0258589
X0314940Y0252083
X0291943Y0162630
X0296523Y0162585
X0281193Y0241624
X0276617Y0241400
X0271547Y0245353
X0283086Y0162675
X0287420Y0162540
X0314914Y0238162
X0324709Y0231580
X0320961Y0250105
X0320372Y0225979
X0331046Y0232021
X0329930Y0245684
X0321899Y0238137
X0306267Y0241010
X0318088Y0231820
X0308057Y0248863
X0402512Y0017108
X0375219Y0003002
X0294483Y0067732
X0317567Y0063778
X0313089Y0063778
X0308651Y0063778
X0304151Y0063778
X0299687Y0063778
X0322005Y0063778
X0267627Y0115559
X0333889Y0056021
X0338227Y0061559
X0345089Y0056190
X0359931Y0052189
X0402512Y0117108
X0402512Y0067108
X0325219Y0003002
X0275219Y0003002
X0331403Y0051409
X0340373Y0051579
X0348289Y0050863
X0387524Y0076847
X0379257Y0052158
X0365720Y0052336
X0379572Y0058441
X0372204Y0056126
X0402512Y0217108
X0402512Y0167108
X0402512Y0317108
X0402512Y0267108
X0368907Y0404308
X0363825Y0401768
X0374542Y0401282
X0380878Y0403999
X0380619Y0410112
X0374442Y0406857
X0402512Y0417108
X0402512Y0367108
X0402512Y0517108
X0402512Y0467108
X0402512Y0617108
X0402512Y0567108
X0402512Y0717108
X0402512Y0667108
X0380186Y0761742
X0376654Y0754748
X0391278Y0765894
X0386790Y0774338
X0382892Y0767710
X0362577Y0752783
X0402512Y0817108
X0402512Y0767108
X0402512Y0917108
X0402512Y0867108
X0402512Y1017108
X0402512Y0967108
X0402512Y1117108
X0402512Y1067108
X0371523Y1204725
X0386816Y1179841
X0383276Y1184136
X0373674Y1199967
X0376472Y1194999
X0379335Y1189778
X0402512Y1217108
X0402512Y1167108
X0402512Y1317108
X0402512Y1267108
X0402512Y1417108
X0402512Y1367108
X0402512Y1517108
X0402512Y1467108
X0402512Y1617108
X0402512Y1567108
X0367829Y1566108
X0361011Y1568890
X0402512Y1717108
X0402512Y1667108
X0402512Y1817108
X0402512Y1767108
X0402512Y1917108
X0402512Y1867108
X0369748Y1921795
X0379403Y1917261
X0363411Y1923459
X0363361Y1918313
X0374775Y1919243
X0402512Y2017108
X0402512Y1967108
X0359991Y2083607
X0402512Y2067108
M00
X0152091Y1873222
X0159519Y1873222
X0159519Y1866003
X0152091Y1866003
X0159348Y1895219
X0159519Y1880706
X0159519Y1887301
X0152091Y1887301
X0152091Y1880706
X0151920Y1895219
X0159348Y1918217
X0159348Y1910698
X0159348Y1902662
X0151920Y1918217
X0151920Y1910698
X0151920Y1902662
X0158492Y1657248
X0158492Y1667763
X0158492Y1678268
X0158492Y1687605
X0158492Y1695333
X0158492Y1703772
X0154109Y1506440
X0154109Y1499221
X0154109Y1520519
X0154109Y1513924
X0153938Y1528437
X0153938Y1551435
X0153938Y1543916
X0153938Y1535880
X0155749Y1354257
X0155749Y1318248
X0155749Y1307733
X0155749Y1345818
X0155749Y1338090
X0155749Y1328753
X0153124Y1169037
X0153124Y1183740
X0153124Y1190335
X0153124Y1176256
X0152953Y1198253
X0155273Y0852165
X0155273Y0867720
X0155273Y0860201
X0155444Y0830209
X0155444Y0822725
X0155273Y0844722
X0155444Y0836804
X0157272Y0624079
X0157272Y0604773
X0157272Y0613574
X0157272Y0649583
X0157272Y0633416
X0157272Y0641144
X0156430Y0476417
X0156430Y0468933
X0156430Y0461714
X0156259Y0506409
X0156259Y0498373
X0156259Y0490930
X0156430Y0483012
X0156259Y0513928
X0256566Y0045572
X0240955Y0056999
X0173928Y0111407
X0173928Y0118626
X0166500Y0111407
X0166500Y0118626
X0240784Y0086439
X0240955Y0071078
X0240784Y0078996
X0240955Y0064483
X0173757Y0148066
X0166329Y0148066
X0173928Y0132705
X0173757Y0140623
X0173928Y0126110
X0166500Y0132705
X0166500Y0126110
X0166329Y0140623
X0240784Y0101994
X0240784Y0094475
X0248451Y0056999
X0248280Y0086439
X0248451Y0071078
X0248280Y0078996
X0248451Y0064483
X0248280Y0101994
X0248280Y0094475
X0256566Y0054944
X0256566Y0065449
X0244033Y0244995
X0227714Y0244995
X0227714Y0237776
X0236537Y0244995
X0173757Y0163621
X0173757Y0156102
X0166329Y0163621
X0166329Y0156102
X0252818Y0221664
X0252818Y0232179
X0252818Y0242684
X0252818Y0252021
X0232700Y0161692
X0232700Y0153964
X0232700Y0170131
X0222732Y0161692
X0222732Y0153964
X0222732Y0170131
X0253083Y0161692
X0253083Y0153964
X0253083Y0170131
X0243741Y0161692
X0243741Y0153964
X0243741Y0170131
X0175033Y0276297
X0175033Y0268813
X0175033Y0261594
X0174862Y0306289
X0174862Y0298253
X0174862Y0290810
X0175033Y0282892
X0174862Y0313808
X0244033Y0252479
X0227714Y0252479
X0236537Y0252479
X0243862Y0282471
X0243862Y0274435
X0243862Y0266992
X0244033Y0259074
X0227543Y0282471
X0236366Y0282471
X0227543Y0274435
X0227543Y0266992
X0227714Y0259074
X0236366Y0274435
X0236366Y0266992
X0236537Y0259074
X0243862Y0289990
X0227543Y0289990
X0236366Y0289990
X0165975Y0265783
X0165975Y0276298
X0165975Y0286803
X0165975Y0303868
X0165975Y0296140
X0165975Y0312307
X0252818Y0259749
X0252818Y0268188
X0239746Y0417898
X0239746Y0396878
X0239746Y0407393
X0248714Y0418041
X0257572Y0417650
X0248714Y0397021
X0248714Y0407536
X0257572Y0407145
X0257572Y0396630
X0248867Y0475786
X0248867Y0468302
X0232548Y0475786
X0232548Y0468302
X0232548Y0461083
X0241371Y0475786
X0241371Y0468302
X0248696Y0505778
X0248696Y0497742
X0248696Y0490299
X0248867Y0482381
X0232377Y0505778
X0241200Y0505778
X0232377Y0497742
X0232377Y0490299
X0232548Y0482381
X0241200Y0497742
X0241200Y0490299
X0241371Y0482381
X0248696Y0513297
X0232377Y0513297
X0241200Y0513297
X0247214Y0594029
X0247214Y0601513
X0230963Y0594029
X0238391Y0594029
X0238391Y0601513
X0230963Y0601513
X0247214Y0608108
X0247043Y0616026
X0247043Y0623469
X0238391Y0608108
X0230963Y0608108
X0238220Y0616026
X0230792Y0616026
X0238220Y0623469
X0230792Y0623469
X0247043Y0631505
X0247043Y0639024
X0238220Y0631505
X0230792Y0631505
X0238220Y0639024
X0230792Y0639024
X0254710Y0594029
X0254710Y0601513
X0254710Y0608108
X0254539Y0616026
X0254539Y0623469
X0254539Y0631505
X0254539Y0639024
X0162872Y0830209
X0162872Y0822725
X0162701Y0844722
X0162872Y0836804
X0171695Y0830209
X0171695Y0822725
X0179191Y0830209
X0179191Y0822725
X0171524Y0844722
X0179020Y0844722
X0171695Y0836804
X0179191Y0836804
X0234012Y0770949
X0234012Y0754782
X0234012Y0762510
X0255021Y0770949
X0243980Y0770949
X0255021Y0754782
X0243980Y0754782
X0243980Y0762510
X0255021Y0762510
X0162701Y0852165
X0162701Y0867720
X0162701Y0860201
X0171524Y0852165
X0179020Y0852165
X0171524Y0867720
X0179020Y0867720
X0171524Y0860201
X0179020Y0860201
X0251396Y0871326
X0251396Y0855159
X0251396Y0862887
X0231339Y0952454
X0238767Y0952454
X0231339Y0967157
X0231339Y0973752
X0238767Y0973752
X0238767Y0967157
X0238767Y0959673
X0231339Y0959673
X0231168Y0989113
X0231168Y0997149
X0238596Y0989113
X0238596Y0997149
X0231168Y0981670
X0238596Y0981670
X0231168Y1004668
X0238596Y1004668
X0247590Y0967157
X0247590Y0973752
X0247590Y0959673
X0255086Y0967157
X0255086Y0973752
X0255086Y0959673
X0247419Y0989113
X0247419Y0997149
X0247419Y0981670
X0254915Y0989113
X0254915Y0997149
X0254915Y0981670
X0247419Y1004668
X0254915Y1004668
X0166699Y0993944
X0166699Y0972924
X0166699Y0983439
X0166424Y1019737
X0166424Y1003570
X0166424Y1011298
X0251251Y1134879
X0251251Y1124364
X0251251Y1145384
X0160552Y1169037
X0160552Y1190335
X0160552Y1183740
X0160552Y1176256
X0231231Y1199741
X0231231Y1207777
X0238659Y1199741
X0238659Y1207777
X0160381Y1198253
X0231231Y1215296
X0238659Y1215296
X0169375Y1183740
X0169375Y1190335
X0169375Y1176256
X0176871Y1183740
X0176871Y1190335
X0176871Y1176256
X0247482Y1199741
X0247482Y1207777
X0169204Y1198253
X0254978Y1199741
X0254978Y1207777
X0176700Y1198253
X0247482Y1215296
X0254978Y1215296
X0259581Y1282945
X0259581Y1272430
X0259581Y1310515
X0259581Y1302787
X0259581Y1293450
X0259581Y1318954
X0219214Y1294491
X0219214Y1287272
X0242961Y1294491
X0235465Y1294491
X0226642Y1294491
X0226642Y1287272
X0219349Y1308924
X0219178Y1316842
X0219214Y1301975
X0242925Y1316842
X0243096Y1308924
X0242961Y1301975
X0235429Y1316842
X0235600Y1308924
X0226606Y1316842
X0226777Y1308924
X0235465Y1301975
X0226642Y1301975
X0219178Y1339840
X0219178Y1332321
X0219178Y1324285
X0242925Y1339840
X0242925Y1332321
X0242925Y1324285
X0235429Y1339840
X0235429Y1332321
X0226606Y1339840
X0226606Y1332321
X0235429Y1324285
X0226606Y1324285
X0170360Y1506440
X0161537Y1506440
X0161537Y1499221
X0170189Y1528437
X0161366Y1528437
X0161537Y1513924
X0161537Y1520519
X0170360Y1520519
X0170360Y1513924
X0170189Y1551435
X0161366Y1551435
X0161366Y1543916
X0161366Y1535880
X0170189Y1543916
X0170189Y1535880
X0177856Y1506440
X0177685Y1528437
X0177856Y1520519
X0177856Y1513924
X0177685Y1551435
X0177685Y1543916
X0177685Y1535880
X0224960Y1715381
X0224960Y1699826
X0224960Y1692383
X0224960Y1707862
X0225131Y1677870
X0232388Y1715381
X0225131Y1670386
X0225131Y1684465
X0232388Y1699826
X0232388Y1692383
X0232388Y1707862
X0232559Y1677870
X0232559Y1670386
X0232559Y1684465
X0232559Y1663167
X0248878Y1670386
X0241382Y1670386
X0248707Y1692383
X0248878Y1684465
X0248878Y1677870
X0241382Y1684465
X0241211Y1692383
X0241382Y1677870
X0248707Y1715381
X0248707Y1707862
X0248707Y1699826
X0225131Y1663167
X0241211Y1707862
X0241211Y1715381
X0241211Y1699826
X0254718Y1676593
X0254718Y1687108
X0254718Y1697613
X0254718Y1706950
X0254718Y1714678
X0254457Y1722140
X0250288Y1840090
X0250288Y1833135
X0258459Y1833135
X0258459Y1840090
X0250288Y1826219
X0258459Y1826219
X0250468Y1805203
X0250468Y1812119
X0250468Y1819074
X0258639Y1805203
X0258639Y1812119
X0258639Y1819074
X0168342Y1873222
X0168171Y1895219
X0168342Y1887301
X0168342Y1880706
X0168171Y1918217
X0168171Y1910698
X0168171Y1902662
X0175838Y1873222
X0175667Y1895219
X0175838Y1887301
X0175838Y1880706
X0175667Y1918217
X0175667Y1910698
X0175667Y1902662
X0258337Y2031480
X0258337Y2041985
X0258337Y2051322
X0245582Y2051322
X0245582Y2041985
X0258337Y2020965
X0245582Y2020965
X0245582Y2031480
X0234541Y2020965
X0224573Y2020965
X0234541Y2041985
X0234541Y2031480
X0224573Y2051322
X0224573Y2041985
X0224573Y2031480
X0234541Y2051322
X0258337Y2059050
X0245582Y2059050
X0245582Y2067489
X0224573Y2067489
X0258337Y2067489
X0234541Y2067489
X0234541Y2059050
X0224573Y2059050
X0270115Y2059050
X0270115Y2067489
X0270115Y2020965
X0270115Y2031480
X0270115Y2041985
X0270115Y2051322
X0307215Y1924283
X0307215Y1917328
X0314810Y1924283
X0314810Y1917328
X0314810Y1910412
X0307215Y1910412
X0300349Y1910232
X0292754Y1910232
X0300349Y1917148
X0292754Y1917148
X0300349Y1924103
X0292754Y1924103
X0267037Y1840093
X0267037Y1833138
X0267037Y1826222
X0267396Y1812122
X0267396Y1805206
X0267396Y1819077
X0265759Y1687108
X0265759Y1676593
X0265759Y1697613
X0265759Y1706950
X0265759Y1714678
X0265498Y1722140
X0261564Y1652180
X0261564Y1659908
X0273342Y1659908
X0273342Y1652180
X0273342Y1668347
X0261564Y1668347
X0261564Y1621823
X0273342Y1621823
X0261564Y1632338
X0273342Y1632338
X0273342Y1642843
X0261564Y1642843
X0285995Y1541235
X0285995Y1534319
X0263939Y1541055
X0271534Y1541055
X0271534Y1534139
X0263939Y1534139
X0278400Y1541235
X0278400Y1534319
X0285995Y1548190
X0263939Y1548010
X0271534Y1548010
X0278400Y1548190
X0301066Y1459083
X0301066Y1465999
X0292895Y1465999
X0292895Y1459083
X0300886Y1487015
X0300886Y1480099
X0300886Y1493970
X0301066Y1472954
X0292895Y1472954
X0292715Y1493970
X0292715Y1480099
X0292715Y1487015
X0309823Y1459086
X0309823Y1466002
X0309464Y1480102
X0309464Y1487018
X0309464Y1493973
X0309823Y1472957
X0354391Y1367771
X0354391Y1360043
X0354391Y1376210
X0354391Y1340201
X0354391Y1329686
X0354391Y1350706
X0270622Y1272430
X0270622Y1282945
X0270622Y1310515
X0270622Y1302787
X0270622Y1293450
X0270622Y1318954
X0278182Y1192183
X0278182Y1184455
X0278182Y1200622
X0294691Y1192254
X0286721Y1192040
X0286721Y1184312
X0294691Y1184526
X0286721Y1200479
X0294691Y1200693
X0311936Y1184525
X0311936Y1192253
X0303159Y1192254
X0303159Y1184526
X0303159Y1200693
X0311936Y1200692
X0269975Y1124220
X0269975Y1134735
X0261219Y1134879
X0261219Y1124364
X0269975Y1145240
X0261219Y1145384
X0288363Y1134450
X0279015Y1134592
X0288363Y1123935
X0279015Y1124077
X0279015Y1145097
X0288363Y1144955
X0307143Y1014094
X0318184Y1014094
X0307274Y1001286
X0307078Y1007303
X0318119Y1007303
X0318315Y1001286
X0318040Y1033718
X0306999Y1033718
X0318235Y1020657
X0307194Y1020657
X0307129Y1027081
X0318170Y1027081
X0262621Y0974386
X0262766Y0959859
X0262766Y0967106
X0274399Y0974386
X0274544Y0959859
X0274544Y0967106
X0262621Y0982114
X0262621Y0990553
X0274399Y0982114
X0274399Y0990553
X0263174Y0871326
X0263174Y0862887
X0263174Y0855159
X0262766Y0949344
X0274544Y0949344
X0304146Y0671763
X0315187Y0671763
X0304146Y0652457
X0304146Y0661258
X0315187Y0661258
X0315187Y0652457
X0315187Y0697267
X0304146Y0697267
X0315187Y0681100
X0304146Y0681100
X0304146Y0688828
X0315187Y0688828
X0279044Y0624627
X0267433Y0624321
X0278944Y0591945
X0267166Y0591945
X0267166Y0572639
X0278944Y0572639
X0267166Y0581440
X0278944Y0581440
X0278944Y0617449
X0267166Y0617449
X0267166Y0601282
X0267166Y0609010
X0278944Y0609010
X0278944Y0601282
X0292569Y0532762
X0292569Y0516595
X0292569Y0524323
X0307966Y0532586
X0300537Y0532476
X0307966Y0516419
X0300537Y0516309
X0300537Y0524037
X0307966Y0524147
X0325139Y0532799
X0316791Y0532871
X0316791Y0516704
X0316791Y0524432
X0325139Y0524360
X0325139Y0516632
X0274531Y0417794
X0266040Y0417651
X0266040Y0396631
X0274531Y0396774
X0266040Y0407146
X0274531Y0407289
X0332693Y0311980
X0332775Y0318634
X0332775Y0325935
X0332775Y0342461
X0332775Y0335272
X0332685Y0348655
X0343734Y0311980
X0343816Y0318634
X0343816Y0325935
X0343816Y0342461
X0343816Y0335272
X0343726Y0348655
X0264596Y0259749
X0264596Y0268188
X0264596Y0221664
X0264596Y0232179
X0264596Y0242684
X0264596Y0252021
X0264861Y0153964
X0264861Y0161692
X0264861Y0170131
X0264104Y0054944
X0264104Y0065449
X0279754Y0054944
X0279754Y0065449
X0271572Y0054944
X0271572Y0065449
X0288102Y0054944
X0288102Y0065449
X0264104Y0045572
X0279754Y0045572
X0271572Y0045572
X0288102Y0045572
X0366169Y1340201
X0366169Y1329686
X0366169Y1350706
X0366169Y1360043
X0366169Y1367771
X0366169Y1376210
M00
X0055511Y0124803
X0051574Y0114960
X0055511Y0105117
X0055511Y0474803
X0051574Y0464960
X0055511Y0455117
X0055511Y0824803
X0051574Y0814960
X0055511Y0805117
X0055511Y1174803
X0051574Y1164960
X0055511Y1155117
X0055511Y1524803
X0051574Y1514960
X0055511Y1505117
X0055511Y1874803
X0051574Y1864960
X0055511Y1855117
X0065354Y1878740
X0075197Y1855117
X0079134Y1864960
X0075197Y1874803
X0065354Y1851180
X0065354Y1528740
X0065354Y1501180
X0075197Y1505117
X0079134Y1514960
X0075197Y1524803
X0065354Y1178740
X0075197Y1155117
X0079134Y1164960
X0075197Y1174803
X0065354Y1151180
X0065354Y0828740
X0065354Y0801180
X0075197Y0805117
X0079134Y0814960
X0075197Y0824803
X0065354Y0478740
X0075197Y0455117
X0079134Y0464960
X0075197Y0474803
X0065354Y0451180
X0065354Y0128740
X0065354Y0101180
X0075197Y0105117
X0079134Y0114960
X0075197Y0124803
X0307087Y2057283
X0297244Y2053346
X0316930Y2053346
X0293307Y2043503
X0297244Y2033660
X0307087Y2029723
X0316930Y2033660
X0320867Y2043503
X0307086Y1707284
X0297243Y1703347
X0293306Y1693504
X0297243Y1683661
X0307086Y1679724
X0316929Y1683661
X0320866Y1693504
X0316929Y1703347
X0307086Y1357284
X0297243Y1353347
X0316929Y1353347
X0293306Y1343504
X0297243Y1333661
X0307086Y1329724
X0316929Y1333661
X0320866Y1343504
X0307086Y0840945
X0297243Y0837008
X0293306Y0827165
X0297243Y0817322
X0307086Y0813385
X0316929Y0817322
X0320866Y0827165
X0316929Y0837008
X0307086Y0490945
X0297243Y0487008
X0293306Y0477165
X0297243Y0467322
X0307086Y0463385
X0316929Y0467322
X0320866Y0477165
X0316929Y0487008
X0307086Y0140945
X0297243Y0137008
X0293306Y0127165
X0297243Y0117322
X0307086Y0113385
X0316929Y0117322
X0320866Y0127165
X0316929Y0137008
M00
X0033263Y0750671
X0033263Y0742797
X0033263Y0734923
X0033263Y0727049
X0033263Y0719175
X0033263Y0711301
X0033263Y0703427
X0007673Y0750671
X0007673Y0742797
X0007673Y0734923
X0007673Y0727049
X0007673Y0719175
X0007673Y0711301
X0007673Y0703427
X0025389Y0746734
X0025389Y0738860
X0025389Y0730986
X0025389Y0723112
X0025389Y0715238
X0025389Y0707364
X0015547Y0746734
X0015547Y0738860
X0015547Y0730986
X0015547Y0723112
X0015547Y0715238
X0015547Y0707364
X0033263Y0845160
X0033263Y0837286
X0033263Y0829412
X0033263Y0821538
X0033263Y0813664
X0033263Y0805790
X0033263Y0797915
X0033263Y0790041
X0033263Y0782167
X0033263Y0774293
X0033263Y0766419
X0033263Y0758545
X0007673Y0845160
X0007673Y0837286
X0007673Y0829412
X0007673Y0821538
X0007673Y0813664
X0007673Y0805790
X0007673Y0797915
X0007673Y0790041
X0007673Y0782167
X0007673Y0774293
X0007673Y0766419
X0007673Y0758545
X0025389Y0849097
X0025389Y0841223
X0025389Y0833349
X0025389Y0825475
X0025389Y0817601
X0025389Y0809727
X0025389Y0801853
X0025389Y0793979
X0025389Y0786105
X0025389Y0778231
X0025389Y0770357
X0025389Y0762483
X0025389Y0754608
X0015547Y0849097
X0015547Y0841223
X0015547Y0833349
X0015547Y0825475
X0015547Y0817601
X0015547Y0809727
X0015547Y0801853
X0015547Y0793979
X0015547Y0786105
X0015547Y0778231
X0015547Y0770357
X0015547Y0762483
X0015547Y0754608
X0033263Y0947522
X0033263Y0939648
X0033263Y0931774
X0033263Y0923900
X0033263Y0916026
X0033263Y0908152
X0033263Y0900278
X0033263Y0892404
X0033263Y0884530
X0033263Y0876656
X0033263Y0868782
X0033263Y0860908
X0033263Y0853034
X0007673Y0947522
X0007673Y0939648
X0007673Y0931774
X0007673Y0923900
X0007673Y0916026
X0007673Y0908152
X0007673Y0900278
X0007673Y0892404
X0007673Y0884530
X0007673Y0876656
X0007673Y0868782
X0007673Y0860908
X0007673Y0853034
X0025389Y0951459
X0025389Y0943585
X0025389Y0935711
X0025389Y0927837
X0025389Y0919963
X0025389Y0912089
X0025389Y0904215
X0025389Y0896341
X0025389Y0888467
X0025389Y0880593
X0025389Y0872719
X0025389Y0864845
X0025389Y0856971
X0015547Y0951459
X0015547Y0943585
X0015547Y0935711
X0015547Y0927837
X0015547Y0919963
X0015547Y0912089
X0015547Y0904215
X0015547Y0896341
X0015547Y0888467
X0015547Y0880593
X0015547Y0872719
X0015547Y0864845
X0015547Y0856971
X0025389Y1030199
X0025389Y1022325
X0025389Y1014451
X0025389Y1006577
X0025389Y0998703
X0025389Y0990829
X0015547Y1030199
X0015547Y1022325
X0015547Y1014451
X0015547Y1006577
X0015547Y0998703
X0015547Y0990829
X0033263Y1026262
X0033263Y1018388
X0033263Y1010514
X0033263Y1002640
X0033263Y0994766
X0007673Y1026262
X0007673Y1018388
X0007673Y1010514
X0007673Y1002640
X0007673Y0994766
X0033263Y0979018
X0033263Y0971144
X0033263Y0963270
X0033263Y0955396
X0007673Y0979018
X0007673Y0971144
X0007673Y0963270
X0007673Y0955396
X0025389Y0975081
X0025389Y0967207
X0025389Y0959333
X0015547Y0975081
X0015547Y0967207
X0015547Y0959333
X0033267Y1148306
X0033267Y1140432
X0033267Y1132558
X0033267Y1124684
X0033267Y1116810
X0033267Y1108936
X0033267Y1101062
X0033267Y1093188
X0033267Y1085314
X0033267Y1077440
X0033267Y1069566
X0033267Y1061692
X0007677Y1148306
X0007677Y1140432
X0007677Y1132558
X0007677Y1124684
X0007677Y1116810
X0007677Y1108936
X0007677Y1101062
X0007677Y1093188
X0007677Y1085314
X0007677Y1077440
X0007677Y1069566
X0007677Y1061692
X0025393Y1144370
X0025393Y1136496
X0025393Y1128622
X0025393Y1120748
X0025393Y1112873
X0025393Y1104999
X0025393Y1097125
X0025393Y1089251
X0025393Y1081377
X0025393Y1073503
X0025393Y1065629
X0015551Y1144370
X0015551Y1136496
X0015551Y1128622
X0015551Y1120748
X0015551Y1112873
X0015551Y1104999
X0015551Y1097125
X0015551Y1089251
X0015551Y1081377
X0015551Y1073503
X0015551Y1065629
X0033267Y1250669
X0033267Y1242795
X0033267Y1234921
X0033267Y1227047
X0033267Y1219173
X0033267Y1211299
X0033267Y1203425
X0033267Y1195551
X0033267Y1187677
X0033267Y1179803
X0033267Y1171929
X0033267Y1164055
X0033267Y1156180
X0007677Y1250669
X0007677Y1242795
X0007677Y1234921
X0007677Y1227047
X0007677Y1219173
X0007677Y1211299
X0007677Y1203425
X0007677Y1195551
X0007677Y1187677
X0007677Y1179803
X0007677Y1171929
X0007677Y1164055
X0007677Y1156180
X0025393Y1246732
X0025393Y1238858
X0025393Y1230984
X0025393Y1223110
X0025393Y1215236
X0025393Y1207362
X0025393Y1199488
X0025393Y1191614
X0025393Y1183740
X0025393Y1175866
X0025393Y1167992
X0025393Y1160118
X0025393Y1152244
X0015551Y1246732
X0015551Y1238858
X0015551Y1230984
X0015551Y1223110
X0015551Y1215236
X0015551Y1207362
X0015551Y1199488
X0015551Y1191614
X0015551Y1183740
X0015551Y1175866
X0015551Y1167992
X0015551Y1160118
X0015551Y1152244
X0025393Y1349094
X0015551Y1349094
X0033267Y1337283
X0033267Y1329409
X0033267Y1321535
X0033267Y1313661
X0033267Y1305787
X0033267Y1297913
X0033267Y1290039
X0033267Y1282165
X0033267Y1274291
X0033267Y1266417
X0033267Y1258543
X0007677Y1337283
X0007677Y1329409
X0007677Y1321535
X0007677Y1313661
X0007677Y1305787
X0007677Y1297913
X0007677Y1290039
X0007677Y1282165
X0007677Y1274291
X0007677Y1266417
X0007677Y1258543
X0025393Y1333346
X0025393Y1325472
X0025393Y1317598
X0025393Y1309724
X0025393Y1301850
X0025393Y1293976
X0025393Y1286102
X0025393Y1278228
X0025393Y1270354
X0025393Y1262480
X0025393Y1254606
X0015551Y1333346
X0015551Y1325472
X0015551Y1317598
X0015551Y1309724
X0015551Y1301850
X0015551Y1293976
X0015551Y1286102
X0015551Y1278228
X0015551Y1270354
X0015551Y1262480
X0015551Y1254606
X0025393Y1388464
X0025393Y1380590
X0025393Y1372716
X0025393Y1364842
X0025393Y1356968
X0015551Y1388464
X0015551Y1380590
X0015551Y1372716
X0015551Y1364842
X0015551Y1356968
X0033267Y1384527
X0033267Y1376653
X0033267Y1368779
X0033267Y1360905
X0033267Y1353031
X0007677Y1384527
X0007677Y1376653
X0007677Y1368779
X0007677Y1360905
X0007677Y1353031
M00
X0253385Y0032520
X0253385Y0021890
X0243385Y0021890
X0243385Y0032520
X0233385Y0021890
X0233385Y0032520
X0223385Y0021890
X0223385Y0032520
X0213385Y0021890
X0213385Y0032520
X0203385Y0021890
X0203385Y0032520
X0193385Y0021890
X0193385Y0032520
X0183385Y0021890
X0183385Y0032520
X0173385Y0021890
X0173385Y0032520
X0253385Y0207520
X0253385Y0196890
X0243385Y0196890
X0243385Y0207520
X0233385Y0196890
X0233385Y0207520
X0223385Y0196890
X0223385Y0207520
X0213385Y0196890
X0213385Y0207520
X0203385Y0196890
X0203385Y0207520
X0193385Y0196890
X0193385Y0207520
X0183385Y0196890
X0183385Y0207520
X0173385Y0196890
X0173385Y0207520
X0253385Y0382520
X0253385Y0371890
X0243385Y0371890
X0243385Y0382520
X0233385Y0371890
X0233385Y0382520
X0223385Y0371890
X0223385Y0382520
X0213385Y0371890
X0213385Y0382520
X0203385Y0371890
X0203385Y0382520
X0193385Y0371890
X0193385Y0382520
X0183385Y0371890
X0183385Y0382520
X0173385Y0371890
X0173385Y0382520
X0253386Y0546890
X0243386Y0546890
X0233386Y0546890
X0223386Y0546890
X0213386Y0546890
X0203386Y0546890
X0193386Y0546890
X0183386Y0546890
X0173386Y0546890
X0253386Y0557520
X0243386Y0557520
X0233386Y0557520
X0223386Y0557520
X0213386Y0557520
X0203386Y0557520
X0193386Y0557520
X0183386Y0557520
X0173386Y0557520
X0253386Y0732520
X0253386Y0721890
X0243386Y0721890
X0243386Y0732520
X0233386Y0721890
X0233386Y0732520
X0223386Y0721890
X0223386Y0732520
X0213386Y0721890
X0213386Y0732520
X0203386Y0721890
X0203386Y0732520
X0193386Y0721890
X0193386Y0732520
X0183386Y0721890
X0183386Y0732520
X0173386Y0721890
X0173386Y0732520
X0253385Y0907520
X0253385Y0896890
X0243385Y0896890
X0243385Y0907520
X0233385Y0896890
X0233385Y0907520
X0223385Y0896890
X0223385Y0907520
X0213385Y0896890
X0213385Y0907520
X0203385Y0896890
X0203385Y0907520
X0193385Y0896890
X0193385Y0907520
X0183385Y0896890
X0183385Y0907520
X0173385Y0896890
X0173385Y0907520
X0253385Y1082520
X0253385Y1071890
X0243385Y1071890
X0243385Y1082520
X0233385Y1071890
X0233385Y1082520
X0223385Y1071890
X0223385Y1082520
X0213385Y1071890
X0213385Y1082520
X0203385Y1071890
X0203385Y1082520
X0193385Y1071890
X0193385Y1082520
X0183385Y1071890
X0183385Y1082520
X0173385Y1071890
X0173385Y1082520
X0253385Y1246890
X0243385Y1246890
X0233385Y1246890
X0223385Y1246890
X0213385Y1246890
X0203385Y1246890
X0193385Y1246890
X0183385Y1246890
X0173385Y1246890
X0253385Y1257520
X0243385Y1257520
X0233385Y1257520
X0223385Y1257520
X0213385Y1257520
X0203385Y1257520
X0193385Y1257520
X0183385Y1257520
X0173385Y1257520
X0253385Y1432520
X0253385Y1421890
X0243385Y1421890
X0243385Y1432520
X0233385Y1421890
X0233385Y1432520
X0223385Y1421890
X0223385Y1432520
X0213385Y1421890
X0213385Y1432520
X0203385Y1421890
X0203385Y1432520
X0193385Y1421890
X0193385Y1432520
X0183385Y1421890
X0183385Y1432520
X0173385Y1421890
X0173385Y1432520
X0253385Y1607520
X0253385Y1596890
X0243385Y1596890
X0243385Y1607520
X0233385Y1596890
X0233385Y1607520
X0223385Y1596890
X0223385Y1607520
X0213385Y1596890
X0213385Y1607520
X0203385Y1596890
X0203385Y1607520
X0193385Y1596890
X0193385Y1607520
X0183385Y1596890
X0183385Y1607520
X0173385Y1596890
X0173385Y1607520
X0253385Y1782520
X0253385Y1771890
X0243385Y1771890
X0243385Y1782520
X0233385Y1771890
X0233385Y1782520
X0223385Y1771890
X0223385Y1782520
X0213385Y1771890
X0213385Y1782520
X0203385Y1771890
X0203385Y1782520
X0193385Y1771890
X0193385Y1782520
X0183385Y1771890
X0183385Y1782520
X0173385Y1771890
X0173385Y1782520
X0253385Y1946890
X0243385Y1946890
X0233385Y1946890
X0223385Y1946890
X0213385Y1946890
X0203385Y1946890
X0193385Y1946890
X0183385Y1946890
X0173385Y1946890
X0253385Y1957520
X0243385Y1957520
X0233385Y1957520
X0223385Y1957520
X0213385Y1957520
X0203385Y1957520
X0193385Y1957520
X0183385Y1957520
X0173385Y1957520
X0313385Y1957520
X0323385Y1957520
X0303385Y1957520
X0293385Y1957520
X0283385Y1957520
X0273385Y1957520
X0263385Y1957520
X0357165Y1959705
X0352165Y1954705
X0347165Y1959705
X0342165Y1954705
X0337165Y1959705
X0313385Y1946890
X0323385Y1946890
X0303385Y1946890
X0293385Y1946890
X0283385Y1946890
X0273385Y1946890
X0263385Y1946890
X0357165Y1949705
X0352165Y1944705
X0347165Y1949705
X0342165Y1944705
X0337165Y1949705
X0313385Y1771890
X0323385Y1771890
X0313385Y1782520
X0323385Y1782520
X0303385Y1782520
X0303385Y1771890
X0293385Y1782520
X0293385Y1771890
X0283385Y1782520
X0283385Y1771890
X0273385Y1782520
X0273385Y1771890
X0263385Y1782520
X0263385Y1771890
X0357165Y1784705
X0357165Y1774705
X0352165Y1779705
X0352165Y1769705
X0347165Y1784705
X0347165Y1774705
X0342165Y1779705
X0342165Y1769705
X0337165Y1784705
X0337165Y1774705
X0313385Y1596890
X0323385Y1596890
X0313385Y1607520
X0323385Y1607520
X0303385Y1607520
X0303385Y1596890
X0293385Y1607520
X0293385Y1596890
X0283385Y1607520
X0283385Y1596890
X0273385Y1607520
X0273385Y1596890
X0263385Y1607520
X0263385Y1596890
X0357165Y1609705
X0357165Y1599705
X0352165Y1604705
X0352165Y1594705
X0347165Y1609705
X0347165Y1599705
X0342165Y1604705
X0342165Y1594705
X0337165Y1609705
X0337165Y1599705
X0313385Y1421890
X0323385Y1421890
X0313385Y1432520
X0323385Y1432520
X0303385Y1432520
X0303385Y1421890
X0293385Y1432520
X0293385Y1421890
X0283385Y1432520
X0283385Y1421890
X0273385Y1432520
X0273385Y1421890
X0263385Y1432520
X0263385Y1421890
X0357165Y1434705
X0357165Y1424705
X0352165Y1429705
X0352165Y1419705
X0347165Y1434705
X0347165Y1424705
X0342165Y1429705
X0342165Y1419705
X0337165Y1434705
X0337165Y1424705
X0313385Y1257520
X0323385Y1257520
X0303385Y1257520
X0293385Y1257520
X0283385Y1257520
X0273385Y1257520
X0263385Y1257520
X0357165Y1259705
X0352165Y1254705
X0347165Y1259705
X0342165Y1254705
X0337165Y1259705
X0313385Y1246890
X0323385Y1246890
X0303385Y1246890
X0293385Y1246890
X0283385Y1246890
X0273385Y1246890
X0263385Y1246890
X0357165Y1249705
X0352165Y1244705
X0347165Y1249705
X0342165Y1244705
X0337165Y1249705
X0313385Y1071890
X0323385Y1071890
X0313385Y1082520
X0323385Y1082520
X0303385Y1082520
X0303385Y1071890
X0293385Y1082520
X0293385Y1071890
X0283385Y1082520
X0283385Y1071890
X0273385Y1082520
X0273385Y1071890
X0263385Y1082520
X0263385Y1071890
X0357165Y1084705
X0357165Y1074705
X0352165Y1079705
X0352165Y1069705
X0347165Y1084705
X0347165Y1074705
X0342165Y1079705
X0342165Y1069705
X0337165Y1084705
X0337165Y1074705
X0313385Y0896890
X0323385Y0896890
X0313385Y0907520
X0323385Y0907520
X0303385Y0907520
X0303385Y0896890
X0293385Y0907520
X0293385Y0896890
X0283385Y0907520
X0283385Y0896890
X0273385Y0907520
X0273385Y0896890
X0263385Y0907520
X0263385Y0896890
X0357165Y0909705
X0357165Y0899705
X0352165Y0904705
X0352165Y0894705
X0347165Y0909705
X0347165Y0899705
X0342165Y0904705
X0342165Y0894705
X0337165Y0909705
X0337165Y0899705
X0313386Y0721890
X0323386Y0721890
X0313386Y0732520
X0323386Y0732520
X0303386Y0732520
X0303386Y0721890
X0293386Y0732520
X0293386Y0721890
X0283386Y0732520
X0283386Y0721890
X0273386Y0732520
X0273386Y0721890
X0263386Y0732520
X0263386Y0721890
X0357166Y0734705
X0357166Y0724705
X0352166Y0729705
X0352166Y0719705
X0347166Y0734705
X0347166Y0724705
X0342166Y0729705
X0342166Y0719705
X0337166Y0734705
X0337166Y0724705
X0313386Y0557520
X0323386Y0557520
X0303386Y0557520
X0293386Y0557520
X0283386Y0557520
X0273386Y0557520
X0263386Y0557520
X0357166Y0559705
X0352166Y0554705
X0347166Y0559705
X0342166Y0554705
X0337166Y0559705
X0313386Y0546890
X0323386Y0546890
X0303386Y0546890
X0293386Y0546890
X0283386Y0546890
X0273386Y0546890
X0263386Y0546890
X0357166Y0549705
X0352166Y0544705
X0347166Y0549705
X0342166Y0544705
X0337166Y0549705
X0313385Y0371890
X0323385Y0371890
X0313385Y0382520
X0323385Y0382520
X0303385Y0382520
X0303385Y0371890
X0293385Y0382520
X0293385Y0371890
X0283385Y0382520
X0283385Y0371890
X0273385Y0382520
X0273385Y0371890
X0263385Y0382520
X0263385Y0371890
X0357165Y0384705
X0357165Y0374705
X0352165Y0379705
X0352165Y0369705
X0347165Y0384705
X0347165Y0374705
X0342165Y0379705
X0342165Y0369705
X0337165Y0384705
X0337165Y0374705
X0313385Y0196890
X0323385Y0196890
X0313385Y0207520
X0323385Y0207520
X0303385Y0207520
X0303385Y0196890
X0293385Y0207520
X0293385Y0196890
X0283385Y0207520
X0283385Y0196890
X0273385Y0207520
X0273385Y0196890
X0263385Y0207520
X0263385Y0196890
X0357165Y0209705
X0357165Y0199705
X0352165Y0204705
X0352165Y0194705
X0347165Y0209705
X0347165Y0199705
X0342165Y0204705
X0342165Y0194705
X0337165Y0209705
X0337165Y0199705
X0362165Y0029705
X0362165Y0019705
X0313385Y0021890
X0323385Y0021890
X0313385Y0032520
X0323385Y0032520
X0303385Y0032520
X0303385Y0021890
X0293385Y0032520
X0293385Y0021890
X0283385Y0032520
X0283385Y0021890
X0273385Y0032520
X0273385Y0021890
X0263385Y0032520
X0263385Y0021890
X0357165Y0034705
X0357165Y0024705
X0352165Y0029705
X0352165Y0019705
X0347165Y0034705
X0347165Y0024705
X0342165Y0029705
X0342165Y0019705
X0337165Y0034705
X0337165Y0024705
X0362165Y0204705
X0362165Y0194705
X0362165Y0379705
X0362165Y0369705
X0362166Y0544705
X0362166Y0554705
X0362166Y0729705
X0362166Y0719705
X0362165Y0904705
X0362165Y0894705
X0362165Y1079705
X0362165Y1069705
X0362165Y1244705
X0362165Y1254705
X0362165Y1429705
X0362165Y1419705
X0362165Y1604705
X0362165Y1594705
X0362165Y1779705
X0362165Y1769705
X0362165Y1944705
X0362165Y1954705
M00
X0053995Y0518701
X0043995Y0518701
X0033995Y0518701
X0023995Y0518701
X0048995Y0508701
X0038995Y0508701
X0028995Y0508701
X0018995Y0508701
X0011692Y0559882
X0051495Y0559882
X0021495Y0559882
X0018995Y1612992
X0028995Y1612992
X0038995Y1612992
X0048995Y1612992
X0023995Y1622992
X0033995Y1622992
X0043995Y1622992
X0053995Y1622992
X0011692Y1571811
X0021495Y1571811
X0051495Y1571811
X0061298Y1571811
X0061298Y0559882
X0204069Y0152050
X0190289Y0152050
X0203542Y0073105
X0189762Y0073105
X0204137Y0247568
X0190357Y0247568
X0204597Y0331786
X0190817Y0331786
X0203541Y0421732
X0189761Y0421732
X0204333Y0506517
X0190553Y0506517
X0206668Y0598130
X0192888Y0598130
X0204596Y0681645
X0190816Y0681645
X0205626Y0774526
X0191846Y0774526
X0210091Y0947202
X0196311Y0947202
X0205386Y0856244
X0191606Y0856244
X0209296Y1032544
X0195516Y1032544
X0205030Y1122856
X0191250Y1122856
X0205122Y1206233
X0191342Y1206233
X0205626Y1299104
X0191846Y1299104
X0204332Y1380966
X0190552Y1380966
X0203243Y1474162
X0189463Y1474162
X0204859Y1557277
X0191079Y1557277
X0205923Y1648177
X0192143Y1648177
X0205387Y1731351
X0191607Y1731351
X0205310Y1823227
X0191530Y1823227
X0204069Y1900420
X0190289Y1900420
X0205310Y2043388
X0191530Y2043388
X0205905Y1998730
X0192125Y1998730
M00
X0052735Y0034953
X0042735Y0034953
X0032735Y0034953
X0022735Y0034953
X0047735Y0024953
X0037735Y0024953
X0027735Y0024953
X0017735Y0024953
X0017735Y0206976
X0027735Y0206976
X0037735Y0206976
X0047735Y0206976
X0022735Y0216976
X0032735Y0216976
X0042735Y0216976
X0052735Y0216976
X0052735Y0243811
X0042735Y0243811
X0032735Y0243811
X0022735Y0243811
X0047735Y0233811
X0037735Y0233811
X0027735Y0233811
X0017735Y0233811
X0017735Y0415834
X0027735Y0415834
X0037735Y0415834
X0047735Y0415834
X0022735Y0425834
X0032735Y0425834
X0042735Y0425834
X0052735Y0425834
X0017735Y1947291
X0027735Y1947291
X0037735Y1947291
X0047735Y1947291
X0022735Y1957291
X0032735Y1957291
X0042735Y1957291
X0052735Y1957291
X0017735Y2051661
X0027735Y2051661
X0037735Y2051661
X0047735Y2051661
X0022735Y2061661
X0032735Y2061661
X0042735Y2061661
X0052735Y2061661
M00
X0009606Y0627264
X0017480Y0627264
X0009606Y0599901
X0017480Y0599901
X0009606Y1471949
X0017480Y1471949
X0009606Y1499311
X0017480Y1499311
M00
X0119920Y2068228
X0119920Y2058228
X0139920Y2058228
X0139920Y2068228
X0119920Y2048228
X0119920Y2038228
X0119920Y2028228
X0119920Y2018228
X0119920Y2008228
X0119920Y1998228
X0119920Y1988228
X0119920Y1978228
X0119920Y1968228
X0119920Y1958228
X0139920Y1958228
X0139920Y1968228
X0139920Y1978228
X0139920Y1988228
X0139920Y1998228
X0139920Y2008228
X0139920Y2018228
X0139920Y2028228
X0139920Y2038228
X0139920Y2048228
X0119920Y1948228
X0119920Y1938228
X0119920Y1928228
X0119920Y1918228
X0119920Y1908228
X0119920Y1898228
X0119920Y1888228
X0119920Y1878228
X0119920Y1868228
X0119920Y1858228
X0139920Y1858228
X0139920Y1868228
X0139920Y1878228
X0139920Y1888228
X0139920Y1898228
X0139920Y1908228
X0139920Y1918228
X0139920Y1928228
X0139920Y1938228
X0139920Y1948228
X0119920Y1848228
X0119920Y1838228
X0119920Y1828228
X0119920Y1818228
X0119920Y1808228
X0119920Y1798228
X0119920Y1788228
X0119920Y1778228
X0119920Y1768228
X0119920Y1758228
X0139920Y1758228
X0139920Y1768228
X0139920Y1778228
X0139920Y1788228
X0139920Y1798228
X0139920Y1808228
X0139920Y1818228
X0139920Y1828228
X0139920Y1838228
X0139920Y1848228
X0119920Y1720197
X0119920Y1710197
X0119920Y1700197
X0119920Y1690197
X0119920Y1680197
X0119920Y1670197
X0119920Y1660197
X0139920Y1660197
X0139920Y1670197
X0139920Y1680197
X0139920Y1690197
X0139920Y1700197
X0139920Y1710197
X0139920Y1720197
X0119920Y1650197
X0119920Y1640197
X0119920Y1630197
X0119920Y1620197
X0119920Y1610197
X0119920Y1600197
X0119920Y1590197
X0119920Y1580197
X0119920Y1570197
X0119920Y1560197
X0139920Y1560197
X0139920Y1570197
X0139920Y1580197
X0139920Y1590197
X0139920Y1600197
X0139920Y1610197
X0139920Y1620197
X0139920Y1630197
X0139920Y1640197
X0139920Y1650197
X0119920Y1550197
X0119920Y1540197
X0119920Y1530197
X0119920Y1520197
X0119920Y1510197
X0119920Y1500197
X0119920Y1490197
X0119920Y1480197
X0119920Y1470197
X0119920Y1460197
X0139920Y1460197
X0139920Y1470197
X0139920Y1480197
X0139920Y1490197
X0139920Y1500197
X0139920Y1510197
X0139920Y1520197
X0139920Y1530197
X0139920Y1540197
X0139920Y1550197
X0119920Y1450197
X0119920Y1440197
X0119920Y1430197
X0119920Y1420197
X0119920Y1410197
X0139920Y1410197
X0139920Y1420197
X0139920Y1430197
X0139920Y1440197
X0139920Y1450197
X0119920Y1372165
X0119920Y1362165
X0119920Y1352165
X0139920Y1352165
X0139920Y1362165
X0139920Y1372165
X0119920Y1342165
X0119920Y1332165
X0119920Y1322165
X0119920Y1312165
X0119920Y1302165
X0119920Y1292165
X0119920Y1282165
X0119920Y1272165
X0119920Y1262165
X0119920Y1252165
X0139920Y1252165
X0139920Y1262165
X0139920Y1272165
X0139920Y1282165
X0139920Y1292165
X0139920Y1302165
X0139920Y1312165
X0139920Y1322165
X0139920Y1332165
X0139920Y1342165
X0119920Y1242165
X0119920Y1232165
X0119920Y1222165
X0119920Y1212165
X0119920Y1202165
X0119920Y1192165
X0119920Y1182165
X0119920Y1172165
X0119920Y1162165
X0119920Y1152165
X0139920Y1152165
X0139920Y1162165
X0139920Y1172165
X0139920Y1182165
X0139920Y1192165
X0139920Y1202165
X0139920Y1212165
X0139920Y1222165
X0139920Y1232165
X0139920Y1242165
X0119920Y1142165
X0119920Y1132165
X0119920Y1122165
X0119920Y1112165
X0119920Y1102165
X0119920Y1092165
X0119920Y1082165
X0119920Y1072165
X0119920Y1062165
X0139920Y1062165
X0139920Y1072165
X0139920Y1082165
X0139920Y1092165
X0139920Y1102165
X0139920Y1112165
X0139920Y1122165
X0139920Y1132165
X0139920Y1142165
X0119920Y1024134
X0119920Y1014134
X0119920Y1004134
X0119920Y0994134
X0119920Y0984134
X0119920Y0974134
X0119920Y0964134
X0119920Y0954134
X0139920Y0954134
X0139920Y0964134
X0139920Y0974134
X0139920Y0984134
X0139920Y0994134
X0139920Y1004134
X0139920Y1014134
X0139920Y1024134
X0119920Y0944134
X0119920Y0934134
X0119920Y0924134
X0119920Y0914134
X0119920Y0904134
X0119920Y0894134
X0119920Y0884134
X0119920Y0874134
X0119920Y0864134
X0119920Y0854134
X0139920Y0854134
X0139920Y0864134
X0139920Y0874134
X0139920Y0884134
X0139920Y0894134
X0139920Y0904134
X0139920Y0914134
X0139920Y0924134
X0139920Y0934134
X0139920Y0944134
X0119920Y0844134
X0119920Y0834134
X0119920Y0824134
X0119920Y0814134
X0119920Y0804134
X0119920Y0794134
X0119920Y0784134
X0119920Y0774134
X0119920Y0764134
X0119920Y0754134
X0139920Y0754134
X0139920Y0764134
X0139920Y0774134
X0139920Y0784134
X0139920Y0794134
X0139920Y0804134
X0139920Y0814134
X0139920Y0824134
X0139920Y0834134
X0139920Y0844134
X0119920Y0676102
X0119920Y0666102
X0119920Y0656102
X0139920Y0656102
X0139920Y0666102
X0139920Y0676102
X0119920Y0744134
X0119920Y0734134
X0119920Y0724134
X0119920Y0714134
X0139920Y0714134
X0139920Y0724134
X0139920Y0734134
X0139920Y0744134
X0119920Y0646102
X0119920Y0636102
X0119920Y0626102
X0119920Y0616102
X0119920Y0606102
X0119920Y0596102
X0119920Y0586102
X0119920Y0576102
X0119920Y0566102
X0119920Y0556102
X0139920Y0556102
X0139920Y0566102
X0139920Y0576102
X0139920Y0586102
X0139920Y0596102
X0139920Y0606102
X0139920Y0616102
X0139920Y0626102
X0139920Y0636102
X0139920Y0646102
X0119920Y0546102
X0119920Y0536102
X0119920Y0526102
X0119920Y0516102
X0119920Y0506102
X0119920Y0496102
X0119920Y0486102
X0119920Y0476102
X0119920Y0466102
X0119920Y0456102
X0139920Y0456102
X0139920Y0466102
X0139920Y0476102
X0139920Y0486102
X0139920Y0496102
X0139920Y0506102
X0139920Y0516102
X0139920Y0526102
X0139920Y0536102
X0139920Y0546102
X0119920Y0446102
X0119920Y0436102
X0119920Y0426102
X0119920Y0416102
X0119920Y0406102
X0119920Y0396102
X0119920Y0386102
X0119920Y0376102
X0119920Y0366102
X0139920Y0366102
X0139920Y0376102
X0139920Y0386102
X0139920Y0396102
X0139920Y0406102
X0139920Y0416102
X0139920Y0426102
X0139920Y0436102
X0139920Y0446102
X0119920Y0328071
X0119920Y0318071
X0119920Y0308071
X0119920Y0298071
X0119920Y0288071
X0119920Y0278071
X0119920Y0268071
X0119920Y0258071
X0139920Y0258071
X0139920Y0268071
X0139920Y0278071
X0139920Y0288071
X0139920Y0298071
X0139920Y0308071
X0139920Y0318071
X0139920Y0328071
X0119920Y0248071
X0119920Y0238071
X0119920Y0228071
X0119920Y0218071
X0119920Y0208071
X0119920Y0198071
X0119920Y0188071
X0119920Y0178071
X0119920Y0168071
X0119920Y0158071
X0139920Y0158071
X0139920Y0168071
X0139920Y0178071
X0139920Y0188071
X0139920Y0198071
X0139920Y0208071
X0139920Y0218071
X0139920Y0228071
X0139920Y0238071
X0139920Y0248071
X0119920Y0148071
X0119920Y0138071
X0119920Y0128071
X0119920Y0118071
X0119920Y0108071
X0119920Y0098071
X0119920Y0088071
X0119920Y0078071
X0119920Y0068071
X0119920Y0058071
X0139920Y0058071
X0139920Y0068071
X0139920Y0078071
X0139920Y0088071
X0139920Y0098071
X0139920Y0108071
X0139920Y0118071
X0139920Y0128071
X0139920Y0138071
X0139920Y0148071
X0119920Y0048071
X0119920Y0038071
X0119920Y0028071
X0119920Y0018071
X0139920Y0018071
X0139920Y0028071
X0139920Y0038071
X0139920Y0048071
M00
X0045056Y1751551
X0045056Y1735016
X0045056Y1718480
X0023402Y1751551
X0023402Y1735016
X0023402Y1718480
X0045056Y1701945
X0023402Y1701945
X0045056Y1685410
X0023402Y1685410
X0045056Y1668874
X0023402Y1668874
X0045056Y1784622
X0045056Y1768087
X0023402Y1784622
X0023402Y1768087
X0045056Y1801158
X0023402Y1801158
X0045056Y1817693
X0023402Y1817693
M00
X0005491Y0528544
X0005491Y1603149
X0067499Y1603149
X0067499Y0528544
M00
X0020468Y0696341
X0020468Y0984333
X0020472Y1054606
X0020472Y1342598
M00
X0163385Y0027205
X0163385Y0202205
X0163385Y0377205
X0163386Y0552205
X0163386Y0727205
X0163385Y0902205
X0163385Y1077205
X0163385Y1252205
X0163385Y1427205
X0163385Y1602205
X0163385Y1777205
X0163385Y1952205
X0373385Y0032520
X0373385Y0207520
X0373385Y0382520
X0373386Y0557520
X0373386Y0732520
X0373385Y0907520
X0373385Y1082520
X0373385Y1257520
X0373385Y1432520
X0373385Y1607520
X0373385Y1782520
X0373385Y1957520
M00
X0058995Y0543701
X0013995Y0543701
X0013995Y1587992
X0058995Y1587992
M00
X0057735Y0059953
X0012735Y0059953
X0012735Y0181976
X0057735Y0181976
X0057735Y0268811
X0012735Y0268811
X0012735Y0390834
X0057735Y0390834
X0012735Y1922291
X0057735Y1922291
X0012735Y2026661
X0057735Y2026661
M00
X0065354Y1864960
X0065354Y1514960
X0065354Y1164960
X0065354Y0814960
X0065354Y0464960
X0065354Y0114960
X0307087Y2043503
X0307086Y1693504
X0307086Y1343504
X0307086Y0827165
X0307086Y0477165
X0307086Y0127165
M00
X0307086Y0308267
M00
X0359842Y2003780
X0359842Y1828779
X0359842Y1653780
X0359842Y1478780
X0359842Y1303780
X0359842Y1128779
X0359842Y0953780
X0359842Y0778780
X0359842Y0603779
X0359842Y0428779
X0359842Y0253780
X0359842Y0078780
M30
